(kicad_pcb
	(version 20241229)
	(generator "pcbnew")
	(generator_version "9.0")
	(general
		(thickness 1.599998)
		(legacy_teardrops no)
	)
	(paper "A4")
	(title_block
		(date "2023-02-12")
		(rev "1.1.5")
		(comment 9 "footprints 136-140 of 473")
	)
	(layers
		(0 "F.Cu" signal)
		(4 "In1.Cu" power "In1.GND")
		(6 "In2.Cu" signal)
		(8 "In3.Cu" power "In3.GND")
		(10 "In4.Cu" power "In4.VCC")
		(12 "In5.Cu" signal)
		(14 "In6.Cu" power "In6.VCC")
		(2 "B.Cu" signal)
		(9 "F.Adhes" user "F.Adhesive")
		(11 "B.Adhes" user "B.Adhesive")
		(13 "F.Paste" user)
		(15 "B.Paste" user)
		(5 "F.SilkS" user "F.Silkscreen")
		(7 "B.SilkS" user "B.Silkscreen")
		(1 "F.Mask" user)
		(3 "B.Mask" user)
		(17 "Dwgs.User" user "User.Drawings")
		(19 "Cmts.User" user "User.Comments")
		(21 "Eco1.User" user "User.Eco1")
		(23 "Eco2.User" user "User.Eco2")
		(25 "Edge.Cuts" user)
		(27 "Margin" user)
		(31 "F.CrtYd" user "F.Courtyard")
		(29 "B.CrtYd" user "B.Courtyard")
		(35 "F.Fab" user)
		(33 "B.Fab" user)
	)
	(footprint "antmicro-footprints:LED_0603_1608Metric_G"
		(layer "F.Cu")
		(at 192.186328 64.020008 180)
		(descr "LED SMD 0603 Green")
		(tags "LED SMD 0603 Green")
		(property "Reference" "D1"
			(at 0.786328 0.620008 180)
			(layer "F.SilkS")
			(effects
				(font
					(size 0.7 0.7)
					(thickness 0.15)
				)
				(justify left bottom)
			)
		)
		(property "Value" "LED_G_0603_KP-1608CGCK"
			(at 0 1.6 180)
			(layer "F.Fab")
			(effects
				(font
					(size 0.7 0.7)
					(thickness 0.15)
				)
				(justify left bottom)
			)
		)
		(property "Author" "Antmicro"
			(at 384.372656 128.040016 0)
			(layer "F.Fab")
			(hide yes)
			(effects
				(font
					(size 1 1)
					(thickness 0.15)
				)
			)
		)
		(property "License" "Apache-2.0"
			(at 384.372656 128.040016 0)
			(layer "F.Fab")
			(hide yes)
			(effects
				(font
					(size 1 1)
					(thickness 0.15)
				)
			)
		)
		(property "MPN" "KP-1608CGCK"
			(at 384.372656 128.040016 0)
			(layer "F.Fab")
			(hide yes)
			(effects
				(font
					(size 1 1)
					(thickness 0.15)
				)
			)
		)
		(property "Manufacturer" "Kingbright"
			(at 384.372656 128.040016 0)
			(layer "F.Fab")
			(hide yes)
			(effects
				(font
					(size 1 1)
					(thickness 0.15)
				)
			)
		)
		(sheetname "Interfaces")
		(sheetfile "interfaces.kicad_sch")
		(attr smd)
		(fp_line
			(start 1.25 0.32)
			(end 1.25 -0.32)
			(stroke
				(width 0.15)
				(type solid)
			)
			(layer "F.SilkS")
		)
		(fp_line
			(start 0.093672 -8e-06)
			(end 0.293672 -8e-06)
			(stroke
				(width 0.1)
				(type solid)
			)
			(layer "F.SilkS")
		)
		(fp_line
			(start 0.093672 -8e-06)
			(end -0.106328 0.199992)
			(stroke
				(width 0.1)
				(type solid)
			)
			(layer "F.SilkS")
		)
		(fp_line
			(start 0.093672 -0.200008)
			(end 0.093672 0.199992)
			(stroke
				(width 0.1)
				(type solid)
			)
			(layer "F.SilkS")
		)
		(fp_line
			(start -0.106328 -8e-06)
			(end -0.29 0)
			(stroke
				(width 0.1)
				(type solid)
			)
			(layer "F.SilkS")
		)
		(fp_line
			(start -0.106328 -0.200008)
			(end 0.093672 -8e-06)
			(stroke
				(width 0.1)
				(type solid)
			)
			(layer "F.SilkS")
		)
		(fp_line
			(start -0.106328 -0.200008)
			(end -0.106328 0.199992)
			(stroke
				(width 0.1)
				(type solid)
			)
			(layer "F.SilkS")
		)
		(fp_line
			(start -0.27 0.351)
			(end 0.27 0.351)
			(stroke
				(width 0.15)
				(type solid)
			)
			(layer "F.SilkS")
		)
		(fp_line
			(start -0.27 -0.35)
			(end 0.27 -0.35)
			(stroke
				(width 0.15)
				(type solid)
			)
			(layer "F.SilkS")
		)
		(fp_rect
			(start 1.26 0.65)
			(end -1.26 -0.65)
			(stroke
				(width 0.05)
				(type solid)
			)
			(fill no)
			(layer "F.CrtYd")
		)
		(fp_line
			(start 0.199 0.202)
			(end 0.199 -0.1)
			(stroke
				(width 0.15)
				(type solid)
			)
			(layer "F.Fab")
		)
		(fp_line
			(start 0.199 0)
			(end 0.597 0)
			(stroke
				(width 0.15)
				(type solid)
			)
			(layer "F.Fab")
		)
		(fp_line
			(start 0.199 -0.2)
			(end 0.199 -0.1)
			(stroke
				(width 0.15)
				(type solid)
			)
			(layer "F.Fab")
		)
		(fp_line
			(start 0.101 0)
			(end -0.201 -0.2)
			(stroke
				(width 0.15)
				(type solid)
			)
			(layer "F.Fab")
		)
		(fp_line
			(start -0.201 0.202)
			(end 0.101 0)
			(stroke
				(width 0.15)
				(type solid)
			)
			(layer "F.Fab")
		)
		(fp_line
			(start -0.201 0)
			(end -0.201 0.202)
			(stroke
				(width 0.15)
				(type solid)
			)
			(layer "F.Fab")
		)
		(fp_line
			(start -0.201 -0.2)
			(end -0.201 0)
			(stroke
				(width 0.15)
				(type solid)
			)
			(layer "F.Fab")
		)
		(fp_line
			(start -0.599 0)
			(end -0.201 0)
			(stroke
				(width 0.15)
				(type solid)
			)
			(layer "F.Fab")
		)
		(fp_rect
			(start -0.848 -0.4)
			(end 0.85 0.402)
			(stroke
				(width 0.15)
				(type solid)
			)
			(fill no)
			(layer "F.Fab")
		)
		(pad "1" smd rect
			(at -0.75 0)
			(size 0.8 0.8)
			(layers "F.Cu" "F.Mask" "F.Paste")
			(net 459 "3V3_SYS")
			(pinfunction "1")
			(pintype "passive")
		)
		(pad "2" smd rect
			(at 0.75 0)
			(size 0.8 0.8)
			(layers "F.Cu" "F.Mask" "F.Paste")
			(net 206 "Net-(D1-Pad2)")
			(pinfunction "2")
			(pintype "passive")
		)
	)
	(footprint "antmicro-footprints:LED_0603_1608Metric_G"
		(layer "F.Cu")
		(at 196.386328 64.020008 180)
		(descr "LED SMD 0603 Green")
		(tags "LED SMD 0603 Green")
		(property "Reference" "D3"
			(at 0.786328 0.620008 180)
			(layer "F.SilkS")
			(effects
				(font
					(size 0.7 0.7)
					(thickness 0.15)
				)
				(justify left bottom)
			)
		)
		(property "Value" "LED_G_0603_KP-1608CGCK"
			(at 0 1.6 180)
			(layer "F.Fab")
			(effects
				(font
					(size 0.7 0.7)
					(thickness 0.15)
				)
				(justify left bottom)
			)
		)
		(property "Author" "Antmicro"
			(at 392.772656 128.040016 0)
			(layer "F.Fab")
			(hide yes)
			(effects
				(font
					(size 1 1)
					(thickness 0.15)
				)
			)
		)
		(property "License" "Apache-2.0"
			(at 392.772656 128.040016 0)
			(layer "F.Fab")
			(hide yes)
			(effects
				(font
					(size 1 1)
					(thickness 0.15)
				)
			)
		)
		(property "MPN" "KP-1608CGCK"
			(at 392.772656 128.040016 0)
			(layer "F.Fab")
			(hide yes)
			(effects
				(font
					(size 1 1)
					(thickness 0.15)
				)
			)
		)
		(property "Manufacturer" "Kingbright"
			(at 392.772656 128.040016 0)
			(layer "F.Fab")
			(hide yes)
			(effects
				(font
					(size 1 1)
					(thickness 0.15)
				)
			)
		)
		(sheetname "Interfaces")
		(sheetfile "interfaces.kicad_sch")
		(attr smd)
		(fp_line
			(start 1.25 0.32)
			(end 1.25 -0.32)
			(stroke
				(width 0.15)
				(type solid)
			)
			(layer "F.SilkS")
		)
		(fp_line
			(start 0.093672 -8e-06)
			(end 0.293672 -8e-06)
			(stroke
				(width 0.1)
				(type solid)
			)
			(layer "F.SilkS")
		)
		(fp_line
			(start 0.093672 -8e-06)
			(end -0.106328 0.199992)
			(stroke
				(width 0.1)
				(type solid)
			)
			(layer "F.SilkS")
		)
		(fp_line
			(start 0.093672 -0.200008)
			(end 0.093672 0.199992)
			(stroke
				(width 0.1)
				(type solid)
			)
			(layer "F.SilkS")
		)
		(fp_line
			(start -0.106328 -8e-06)
			(end -0.29 0)
			(stroke
				(width 0.1)
				(type solid)
			)
			(layer "F.SilkS")
		)
		(fp_line
			(start -0.106328 -0.200008)
			(end 0.093672 -8e-06)
			(stroke
				(width 0.1)
				(type solid)
			)
			(layer "F.SilkS")
		)
		(fp_line
			(start -0.106328 -0.200008)
			(end -0.106328 0.199992)
			(stroke
				(width 0.1)
				(type solid)
			)
			(layer "F.SilkS")
		)
		(fp_line
			(start -0.27 0.351)
			(end 0.27 0.351)
			(stroke
				(width 0.15)
				(type solid)
			)
			(layer "F.SilkS")
		)
		(fp_line
			(start -0.27 -0.35)
			(end 0.27 -0.35)
			(stroke
				(width 0.15)
				(type solid)
			)
			(layer "F.SilkS")
		)
		(fp_rect
			(start 1.26 0.65)
			(end -1.26 -0.65)
			(stroke
				(width 0.05)
				(type solid)
			)
			(fill no)
			(layer "F.CrtYd")
		)
		(fp_line
			(start 0.199 0.202)
			(end 0.199 -0.1)
			(stroke
				(width 0.15)
				(type solid)
			)
			(layer "F.Fab")
		)
		(fp_line
			(start 0.199 0)
			(end 0.597 0)
			(stroke
				(width 0.15)
				(type solid)
			)
			(layer "F.Fab")
		)
		(fp_line
			(start 0.199 -0.2)
			(end 0.199 -0.1)
			(stroke
				(width 0.15)
				(type solid)
			)
			(layer "F.Fab")
		)
		(fp_line
			(start 0.101 0)
			(end -0.201 -0.2)
			(stroke
				(width 0.15)
				(type solid)
			)
			(layer "F.Fab")
		)
		(fp_line
			(start -0.201 0.202)
			(end 0.101 0)
			(stroke
				(width 0.15)
				(type solid)
			)
			(layer "F.Fab")
		)
		(fp_line
			(start -0.201 0)
			(end -0.201 0.202)
			(stroke
				(width 0.15)
				(type solid)
			)
			(layer "F.Fab")
		)
		(fp_line
			(start -0.201 -0.2)
			(end -0.201 0)
			(stroke
				(width 0.15)
				(type solid)
			)
			(layer "F.Fab")
		)
		(fp_line
			(start -0.599 0)
			(end -0.201 0)
			(stroke
				(width 0.15)
				(type solid)
			)
			(layer "F.Fab")
		)
		(fp_rect
			(start -0.848 -0.4)
			(end 0.85 0.402)
			(stroke
				(width 0.15)
				(type solid)
			)
			(fill no)
			(layer "F.Fab")
		)
		(pad "1" smd rect
			(at -0.75 0)
			(size 0.8 0.8)
			(layers "F.Cu" "F.Mask" "F.Paste")
			(net 459 "3V3_SYS")
			(pinfunction "1")
			(pintype "passive")
		)
		(pad "2" smd rect
			(at 0.75 0)
			(size 0.8 0.8)
			(layers "F.Cu" "F.Mask" "F.Paste")
			(net 73 "Net-(D3-Pad2)")
			(pinfunction "2")
			(pintype "passive")
		)
	)
	(footprint "antmicro-footprints:LED_0603_1608Metric_G"
		(layer "F.Cu")
		(at 204.886328 64.020008 180)
		(descr "LED SMD 0603 Green")
		(tags "LED SMD 0603 Green")
		(property "Reference" "D5"
			(at 0.786328 0.620008 180)
			(layer "F.SilkS")
			(effects
				(font
					(size 0.7 0.7)
					(thickness 0.15)
				)
				(justify left bottom)
			)
		)
		(property "Value" "LED_G_0603_KP-1608CGCK"
			(at 0 1.6 180)
			(layer "F.Fab")
			(effects
				(font
					(size 0.7 0.7)
					(thickness 0.15)
				)
				(justify left bottom)
			)
		)
		(property "Author" "Antmicro"
			(at 409.772656 128.040016 0)
			(layer "F.Fab")
			(hide yes)
			(effects
				(font
					(size 1 1)
					(thickness 0.15)
				)
			)
		)
		(property "License" "Apache-2.0"
			(at 409.772656 128.040016 0)
			(layer "F.Fab")
			(hide yes)
			(effects
				(font
					(size 1 1)
					(thickness 0.15)
				)
			)
		)
		(property "MPN" "KP-1608CGCK"
			(at 409.772656 128.040016 0)
			(layer "F.Fab")
			(hide yes)
			(effects
				(font
					(size 1 1)
					(thickness 0.15)
				)
			)
		)
		(property "Manufacturer" "Kingbright"
			(at 409.772656 128.040016 0)
			(layer "F.Fab")
			(hide yes)
			(effects
				(font
					(size 1 1)
					(thickness 0.15)
				)
			)
		)
		(sheetname "Interfaces")
		(sheetfile "interfaces.kicad_sch")
		(attr smd)
		(fp_line
			(start 1.25 0.32)
			(end 1.25 -0.32)
			(stroke
				(width 0.15)
				(type solid)
			)
			(layer "F.SilkS")
		)
		(fp_line
			(start 0.093672 -8e-06)
			(end 0.293672 -8e-06)
			(stroke
				(width 0.1)
				(type solid)
			)
			(layer "F.SilkS")
		)
		(fp_line
			(start 0.093672 -8e-06)
			(end -0.106328 0.199992)
			(stroke
				(width 0.1)
				(type solid)
			)
			(layer "F.SilkS")
		)
		(fp_line
			(start 0.093672 -0.200008)
			(end 0.093672 0.199992)
			(stroke
				(width 0.1)
				(type solid)
			)
			(layer "F.SilkS")
		)
		(fp_line
			(start -0.106328 -8e-06)
			(end -0.29 0)
			(stroke
				(width 0.1)
				(type solid)
			)
			(layer "F.SilkS")
		)
		(fp_line
			(start -0.106328 -0.200008)
			(end 0.093672 -8e-06)
			(stroke
				(width 0.1)
				(type solid)
			)
			(layer "F.SilkS")
		)
		(fp_line
			(start -0.106328 -0.200008)
			(end -0.106328 0.199992)
			(stroke
				(width 0.1)
				(type solid)
			)
			(layer "F.SilkS")
		)
		(fp_line
			(start -0.27 0.351)
			(end 0.27 0.351)
			(stroke
				(width 0.15)
				(type solid)
			)
			(layer "F.SilkS")
		)
		(fp_line
			(start -0.27 -0.35)
			(end 0.27 -0.35)
			(stroke
				(width 0.15)
				(type solid)
			)
			(layer "F.SilkS")
		)
		(fp_rect
			(start 1.26 0.65)
			(end -1.26 -0.65)
			(stroke
				(width 0.05)
				(type solid)
			)
			(fill no)
			(layer "F.CrtYd")
		)
		(fp_line
			(start 0.199 0.202)
			(end 0.199 -0.1)
			(stroke
				(width 0.15)
				(type solid)
			)
			(layer "F.Fab")
		)
		(fp_line
			(start 0.199 0)
			(end 0.597 0)
			(stroke
				(width 0.15)
				(type solid)
			)
			(layer "F.Fab")
		)
		(fp_line
			(start 0.199 -0.2)
			(end 0.199 -0.1)
			(stroke
				(width 0.15)
				(type solid)
			)
			(layer "F.Fab")
		)
		(fp_line
			(start 0.101 0)
			(end -0.201 -0.2)
			(stroke
				(width 0.15)
				(type solid)
			)
			(layer "F.Fab")
		)
		(fp_line
			(start -0.201 0.202)
			(end 0.101 0)
			(stroke
				(width 0.15)
				(type solid)
			)
			(layer "F.Fab")
		)
		(fp_line
			(start -0.201 0)
			(end -0.201 0.202)
			(stroke
				(width 0.15)
				(type solid)
			)
			(layer "F.Fab")
		)
		(fp_line
			(start -0.201 -0.2)
			(end -0.201 0)
			(stroke
				(width 0.15)
				(type solid)
			)
			(layer "F.Fab")
		)
		(fp_line
			(start -0.599 0)
			(end -0.201 0)
			(stroke
				(width 0.15)
				(type solid)
			)
			(layer "F.Fab")
		)
		(fp_rect
			(start -0.848 -0.4)
			(end 0.85 0.402)
			(stroke
				(width 0.15)
				(type solid)
			)
			(fill no)
			(layer "F.Fab")
		)
		(pad "1" smd rect
			(at -0.75 0)
			(size 0.8 0.8)
			(layers "F.Cu" "F.Mask" "F.Paste")
			(net 459 "3V3_SYS")
			(pinfunction "1")
			(pintype "passive")
		)
		(pad "2" smd rect
			(at 0.75 0)
			(size 0.8 0.8)
			(layers "F.Cu" "F.Mask" "F.Paste")
			(net 52 "Net-(D5-Pad2)")
			(pinfunction "2")
			(pintype "passive")
		)
	)
	(footprint "antmicro-footprints:LED_0603_1608Metric_G"
		(layer "F.Cu")
		(at 208.486328 64.020008 180)
		(descr "LED SMD 0603 Green")
		(tags "LED SMD 0603 Green")
		(property "Reference" "D6"
			(at 0.786328 0.620008 180)
			(layer "F.SilkS")
			(effects
				(font
					(size 0.7 0.7)
					(thickness 0.15)
				)
				(justify left bottom)
			)
		)
		(property "Value" "LED_G_0603_KP-1608CGCK"
			(at 0 1.6 180)
			(layer "F.Fab")
			(effects
				(font
					(size 0.7 0.7)
					(thickness 0.15)
				)
				(justify left bottom)
			)
		)
		(property "Author" "Antmicro"
			(at 416.972656 128.040016 0)
			(layer "F.Fab")
			(hide yes)
			(effects
				(font
					(size 1 1)
					(thickness 0.15)
				)
			)
		)
		(property "License" "Apache-2.0"
			(at 416.972656 128.040016 0)
			(layer "F.Fab")
			(hide yes)
			(effects
				(font
					(size 1 1)
					(thickness 0.15)
				)
			)
		)
		(property "MPN" "KP-1608CGCK"
			(at 416.972656 128.040016 0)
			(layer "F.Fab")
			(hide yes)
			(effects
				(font
					(size 1 1)
					(thickness 0.15)
				)
			)
		)
		(property "Manufacturer" "Kingbright"
			(at 416.972656 128.040016 0)
			(layer "F.Fab")
			(hide yes)
			(effects
				(font
					(size 1 1)
					(thickness 0.15)
				)
			)
		)
		(sheetname "Interfaces")
		(sheetfile "interfaces.kicad_sch")
		(attr smd)
		(fp_line
			(start 1.25 0.32)
			(end 1.25 -0.32)
			(stroke
				(width 0.15)
				(type solid)
			)
			(layer "F.SilkS")
		)
		(fp_line
			(start 0.093672 -8e-06)
			(end 0.293672 -8e-06)
			(stroke
				(width 0.1)
				(type solid)
			)
			(layer "F.SilkS")
		)
		(fp_line
			(start 0.093672 -8e-06)
			(end -0.106328 0.199992)
			(stroke
				(width 0.1)
				(type solid)
			)
			(layer "F.SilkS")
		)
		(fp_line
			(start 0.093672 -0.200008)
			(end 0.093672 0.199992)
			(stroke
				(width 0.1)
				(type solid)
			)
			(layer "F.SilkS")
		)
		(fp_line
			(start -0.106328 -8e-06)
			(end -0.29 0)
			(stroke
				(width 0.1)
				(type solid)
			)
			(layer "F.SilkS")
		)
		(fp_line
			(start -0.106328 -0.200008)
			(end 0.093672 -8e-06)
			(stroke
				(width 0.1)
				(type solid)
			)
			(layer "F.SilkS")
		)
		(fp_line
			(start -0.106328 -0.200008)
			(end -0.106328 0.199992)
			(stroke
				(width 0.1)
				(type solid)
			)
			(layer "F.SilkS")
		)
		(fp_line
			(start -0.27 0.351)
			(end 0.27 0.351)
			(stroke
				(width 0.15)
				(type solid)
			)
			(layer "F.SilkS")
		)
		(fp_line
			(start -0.27 -0.35)
			(end 0.27 -0.35)
			(stroke
				(width 0.15)
				(type solid)
			)
			(layer "F.SilkS")
		)
		(fp_rect
			(start 1.26 0.65)
			(end -1.26 -0.65)
			(stroke
				(width 0.05)
				(type solid)
			)
			(fill no)
			(layer "F.CrtYd")
		)
		(fp_line
			(start 0.199 0.202)
			(end 0.199 -0.1)
			(stroke
				(width 0.15)
				(type solid)
			)
			(layer "F.Fab")
		)
		(fp_line
			(start 0.199 0)
			(end 0.597 0)
			(stroke
				(width 0.15)
				(type solid)
			)
			(layer "F.Fab")
		)
		(fp_line
			(start 0.199 -0.2)
			(end 0.199 -0.1)
			(stroke
				(width 0.15)
				(type solid)
			)
			(layer "F.Fab")
		)
		(fp_line
			(start 0.101 0)
			(end -0.201 -0.2)
			(stroke
				(width 0.15)
				(type solid)
			)
			(layer "F.Fab")
		)
		(fp_line
			(start -0.201 0.202)
			(end 0.101 0)
			(stroke
				(width 0.15)
				(type solid)
			)
			(layer "F.Fab")
		)
		(fp_line
			(start -0.201 0)
			(end -0.201 0.202)
			(stroke
				(width 0.15)
				(type solid)
			)
			(layer "F.Fab")
		)
		(fp_line
			(start -0.201 -0.2)
			(end -0.201 0)
			(stroke
				(width 0.15)
				(type solid)
			)
			(layer "F.Fab")
		)
		(fp_line
			(start -0.599 0)
			(end -0.201 0)
			(stroke
				(width 0.15)
				(type solid)
			)
			(layer "F.Fab")
		)
		(fp_rect
			(start -0.848 -0.4)
			(end 0.85 0.402)
			(stroke
				(width 0.15)
				(type solid)
			)
			(fill no)
			(layer "F.Fab")
		)
		(pad "1" smd rect
			(at -0.75 0)
			(size 0.8 0.8)
			(layers "F.Cu" "F.Mask" "F.Paste")
			(net 459 "3V3_SYS")
			(pinfunction "1")
			(pintype "passive")
		)
		(pad "2" smd rect
			(at 0.75 0)
			(size 0.8 0.8)
			(layers "F.Cu" "F.Mask" "F.Paste")
			(net 53 "Net-(D6-Pad2)")
			(pinfunction "2")
			(pintype "passive")
		)
	)
	(footprint "antmicro-footprints:R_0402_1005Metric"
		(layer "F.Cu")
		(at 190.736328 71.697157 -90)
		(descr "Resistor SMD 0402")
		(tags "resistor SMD 0402")
		(property "Reference" "R26"
			(at 1.102843 -1.263672 270)
			(layer "F.SilkS")
			(effects
				(font
					(size 0.7 0.7)
					(thickness 0.15)
				)
				(justify left bottom)
			)
		)
		(property "Value" "R_330R_0402"
			(at 0 1.4 270)
			(layer "F.Fab")
			(effects
				(font
					(size 0.7 0.7)
					(thickness 0.15)
				)
				(justify left bottom)
			)
		)
		(property "Description" "330R resistor in 0402 package with 1% tolerance"
			(at 0 0 270)
			(layer "F.Fab")
			(hide yes)
			(effects
				(font
					(size 1.27 1.27)
					(thickness 0.15)
				)
			)
		)
		(property "Author" "Antmicro"
			(at 119.039171 262.433485 0)
			(layer "F.Fab")
			(hide yes)
			(effects
				(font
					(size 1 1)
					(thickness 0.15)
				)
			)
		)
		(property "License" "Apache-2.0"
			(at 119.039171 262.433485 0)
			(layer "F.Fab")
			(hide yes)
			(effects
				(font
					(size 1 1)
					(thickness 0.15)
				)
			)
		)
		(property "MPN" "CR0402-FX-3300GLF"
			(at 119.039171 262.433485 0)
			(layer "F.Fab")
			(hide yes)
			(effects
				(font
					(size 1 1)
					(thickness 0.15)
				)
			)
		)
		(property "Manufacturer" "Bourns"
			(at 119.039171 262.433485 0)
			(layer "F.Fab")
			(hide yes)
			(effects
				(font
					(size 1 1)
					(thickness 0.15)
				)
			)
		)
		(property "Tolerance" "1%"
			(at 119.039171 262.433485 0)
			(layer "F.Fab")
			(hide yes)
			(effects
				(font
					(size 1 1)
					(thickness 0.15)
				)
			)
		)
		(property "Val" "330R"
			(at 119.039171 262.433485 0)
			(layer "F.Fab")
			(hide yes)
			(effects
				(font
					(size 1 1)
					(thickness 0.15)
				)
			)
		)
		(sheetname "Interfaces")
		(sheetfile "interfaces.kicad_sch")
		(attr smd)
		(fp_rect
			(start -0.93 -0.47)
			(end 0.93 0.47)
			(stroke
				(width 0.05)
				(type solid)
			)
			(fill no)
			(layer "F.CrtYd")
		)
		(fp_rect
			(start -0.5 -0.25)
			(end 0.5 0.25)
			(stroke
				(width 0.15)
				(type solid)
			)
			(fill no)
			(layer "F.Fab")
		)
		(pad "1" smd roundrect
			(at -0.485 0 270)
			(size 0.59 0.64)
			(layers "F.Cu" "F.Mask" "F.Paste")
			(roundrect_rratio 0.25)
			(net 206 "Net-(D1-Pad2)")
			(pintype "passive")
		)
		(pad "2" smd roundrect
			(at 0.485 0 270)
			(size 0.59 0.64)
			(layers "F.Cu" "F.Mask" "F.Paste")
			(roundrect_rratio 0.25)
			(net 209 "Net-(Q1-D)")
			(pintype "passive")
		)
	)
)
